# S9S_MB_2U (Grand Teton) — schematic netlist excerpt (pin names and nets, part order shuffled) for the footprints in the layout excerpt that follows; sources: Cadence DE-HDL packaged netlist, KiCad conversion of 03242023_DA0F0TMBIJ0_F0T_Motherboard_J_brd_V01_OCP.brd

R3483  Q_RES  33.2 1% CHIP  pkg 0402LF  page 213 : A = GPU_FPGA_EROT_RECOV_N ; B = GPU_FPGA_EROT_RECOV_R_N
PR285  Q_RES  8.87K 1% EMPTY  pkg 0402LF  page 288 : A = PVCCIN_CPU1_LSET8 ; B = GND

(kicad_pcb
	(version 20260206)
	(generator "pcbnew")
	(generator_version "10.0")
	(general
		(thickness 1.6)
		(legacy_teardrops no)
	)
	(paper "A4")
	(title_block
		(title "03242023_DA0F0TMBIJ0_F0T_Motherboard_J_brd_V01_OCP.brd")
		(comment 1 "Grand Teton / footprints 2697-2698 of 6105")
	)
	(layers
		(0 "F.Cu" signal "TOP")
		(4 "In1.Cu" signal "GND")
		(6 "In2.Cu" signal "IN1")
		(8 "In3.Cu" signal "GND1")
		(10 "In4.Cu" signal "IN2")
		(12 "In5.Cu" signal "GND2")
		(14 "In6.Cu" signal "IN3")
		(16 "In7.Cu" signal "GND3")
		(18 "In8.Cu" signal "VCC")
		(20 "In9.Cu" signal "VCC1")
		(22 "In10.Cu" signal "GND4")
		(24 "In11.Cu" signal "IN4")
		(26 "In12.Cu" signal "GND5")
		(28 "In13.Cu" signal "IN5")
		(30 "In14.Cu" signal "GND6")
		(32 "In15.Cu" signal "IN6")
		(34 "In16.Cu" signal "GND7")
		(2 "B.Cu" signal "BOTTOM")
		(9 "F.Adhes" user "F.Adhesive")
		(11 "B.Adhes" user "B.Adhesive")
		(13 "F.Paste" user "Package Geometry/Pastemask Top")
		(15 "B.Paste" user "Package Geometry/Pastemask Bottom")
		(5 "F.SilkS" user "Ref Des/Silkscreen Top")
		(7 "B.SilkS" user "Ref Des/Silkscreen Bottom")
		(1 "F.Mask" user "Board Geometry/Soldermask Top")
		(3 "B.Mask" user "Board Geometry/Soldermask Bottom")
		(17 "Dwgs.User" user "User.Drawings")
		(19 "Cmts.User" user "User.Comments")
		(21 "Eco1.User" user "User.Eco1")
		(23 "Eco2.User" user "User.Eco2")
		(25 "Edge.Cuts" user "Board Geometry/Outline")
		(27 "Margin" user)
		(31 "F.CrtYd" user "Package Geometry/Place Bound Top")
		(29 "B.CrtYd" user "Package Geometry/Place Bound Bottom")
		(35 "F.Fab" user "Ref Des/Assembly Top")
		(33 "B.Fab" user "Ref Des/Assembly Bottom")
	)
	(footprint ""
		(layer "F.Cu")
		(at 136.508998 -348.061026)
		(property "Reference" "PR285"
			(at 0 0 0)
			(layer "F.SilkS")
			(hide yes)
			(effects
				(font
					(size 1.27 1.27)
				)
			)
		)
		(property "Value" ""
			(at 0 0 0)
			(layer "F.Fab")
			(effects
				(font
					(size 1.27 1.27)
				)
			)
		)
		(duplicate_pad_numbers_are_jumpers no)
		(fp_line
			(start -0.7874 -0.4064)
			(end 0.7874 -0.4064)
			(stroke
				(width 0.1524)
				(type default)
			)
			(layer "F.SilkS")
		)
		(fp_line
			(start -0.7874 0.4064)
			(end -0.7874 -0.4064)
			(stroke
				(width 0.1524)
				(type default)
			)
			(layer "F.SilkS")
		)
		(fp_line
			(start 0.7874 -0.4064)
			(end 0.7874 0.4064)
			(stroke
				(width 0.1524)
				(type default)
			)
			(layer "F.SilkS")
		)
		(fp_line
			(start 0.7874 0.4064)
			(end -0.7874 0.4064)
			(stroke
				(width 0.1524)
				(type default)
			)
			(layer "F.SilkS")
		)
		(fp_line
			(start -0.67945 -0.305054)
			(end -0.12065 -0.305054)
			(stroke
				(width 0.1)
				(type default)
			)
			(layer "F.Fab")
		)
		(fp_line
			(start -0.67945 0.3048)
			(end -0.67945 -0.305054)
			(stroke
				(width 0.1)
				(type default)
			)
			(layer "F.Fab")
		)
		(fp_line
			(start -0.12065 -0.305054)
			(end -0.12065 -0.2794)
			(stroke
				(width 0.1)
				(type default)
			)
			(layer "F.Fab")
		)
		(fp_line
			(start -0.12065 -0.2794)
			(end 0.12065 -0.2794)
			(stroke
				(width 0.1)
				(type default)
			)
			(layer "F.Fab")
		)
		(fp_line
			(start -0.12065 0.2794)
			(end -0.12065 0.3048)
			(stroke
				(width 0.1)
				(type default)
			)
			(layer "F.Fab")
		)
		(fp_line
			(start -0.12065 0.3048)
			(end -0.67945 0.3048)
			(stroke
				(width 0.1)
				(type default)
			)
			(layer "F.Fab")
		)
		(fp_line
			(start 0.120396 0.2794)
			(end -0.12065 0.2794)
			(stroke
				(width 0.1)
				(type default)
			)
			(layer "F.Fab")
		)
		(fp_line
			(start 0.120396 0.3048)
			(end 0.120396 0.2794)
			(stroke
				(width 0.1)
				(type default)
			)
			(layer "F.Fab")
		)
		(fp_line
			(start 0.12065 -0.3048)
			(end 0.67945 -0.3048)
			(stroke
				(width 0.1)
				(type default)
			)
			(layer "F.Fab")
		)
		(fp_line
			(start 0.12065 -0.2794)
			(end 0.12065 -0.3048)
			(stroke
				(width 0.1)
				(type default)
			)
			(layer "F.Fab")
		)
		(fp_line
			(start 0.67945 -0.3048)
			(end 0.67945 0.3048)
			(stroke
				(width 0.1)
				(type default)
			)
			(layer "F.Fab")
		)
		(fp_line
			(start 0.67945 0.3048)
			(end 0.120396 0.3048)
			(stroke
				(width 0.1)
				(type default)
			)
			(layer "F.Fab")
		)
		(pad "1" smd circle
			(at -0.40005 0)
			(size 0 0)
			(layers "F.Cu" "F.Mask" "F.Paste")
			(net "PVCCIN_CPU1_LSET8")
		)
		(pad "2" smd circle
			(at 0.40005 0)
			(size 0 0)
			(layers "F.Cu" "F.Mask" "F.Paste")
			(net "GND")
		)
	)
	(footprint ""
		(layer "F.Cu")
		(at 160.83788 -115.026948)
		(property "Reference" "R3483"
			(at 0 0 0)
			(layer "F.SilkS")
			(hide yes)
			(effects
				(font
					(size 1.27 1.27)
				)
			)
		)
		(property "Value" ""
			(at 0 0 0)
			(layer "F.Fab")
			(effects
				(font
					(size 1.27 1.27)
				)
			)
		)
		(duplicate_pad_numbers_are_jumpers no)
		(fp_line
			(start -0.7874 -0.4064)
			(end 0.7874 -0.4064)
			(stroke
				(width 0.1524)
				(type default)
			)
			(layer "F.SilkS")
		)
		(fp_line
			(start -0.7874 0.4064)
			(end -0.7874 -0.4064)
			(stroke
				(width 0.1524)
				(type default)
			)
			(layer "F.SilkS")
		)
		(fp_line
			(start 0.7874 -0.4064)
			(end 0.7874 0.4064)
			(stroke
				(width 0.1524)
				(type default)
			)
			(layer "F.SilkS")
		)
		(fp_line
			(start 0.7874 0.4064)
			(end -0.7874 0.4064)
			(stroke
				(width 0.1524)
				(type default)
			)
			(layer "F.SilkS")
		)
		(fp_line
			(start -0.67945 -0.305054)
			(end -0.12065 -0.305054)
			(stroke
				(width 0.1)
				(type default)
			)
			(layer "F.Fab")
		)
		(fp_line
			(start -0.67945 0.3048)
			(end -0.67945 -0.305054)
			(stroke
				(width 0.1)
				(type default)
			)
			(layer "F.Fab")
		)
		(fp_line
			(start -0.12065 -0.305054)
			(end -0.12065 -0.2794)
			(stroke
				(width 0.1)
				(type default)
			)
			(layer "F.Fab")
		)
		(fp_line
			(start -0.12065 -0.2794)
			(end 0.12065 -0.2794)
			(stroke
				(width 0.1)
				(type default)
			)
			(layer "F.Fab")
		)
		(fp_line
			(start -0.12065 0.2794)
			(end -0.12065 0.3048)
			(stroke
				(width 0.1)
				(type default)
			)
			(layer "F.Fab")
		)
		(fp_line
			(start -0.12065 0.3048)
			(end -0.67945 0.3048)
			(stroke
				(width 0.1)
				(type default)
			)
			(layer "F.Fab")
		)
		(fp_line
			(start 0.120396 0.2794)
			(end -0.12065 0.2794)
			(stroke
				(width 0.1)
				(type default)
			)
			(layer "F.Fab")
		)
		(fp_line
			(start 0.120396 0.3048)
			(end 0.120396 0.2794)
			(stroke
				(width 0.1)
				(type default)
			)
			(layer "F.Fab")
		)
		(fp_line
			(start 0.12065 -0.3048)
			(end 0.67945 -0.3048)
			(stroke
				(width 0.1)
				(type default)
			)
			(layer "F.Fab")
		)
		(fp_line
			(start 0.12065 -0.2794)
			(end 0.12065 -0.3048)
			(stroke
				(width 0.1)
				(type default)
			)
			(layer "F.Fab")
		)
		(fp_line
			(start 0.67945 -0.3048)
			(end 0.67945 0.3048)
			(stroke
				(width 0.1)
				(type default)
			)
			(layer "F.Fab")
		)
		(fp_line
			(start 0.67945 0.3048)
			(end 0.120396 0.3048)
			(stroke
				(width 0.1)
				(type default)
			)
			(layer "F.Fab")
		)
		(pad "1" smd circle
			(at -0.40005 0)
			(size 0 0)
			(layers "F.Cu" "F.Mask" "F.Paste")
			(net "GPU_FPGA_EROT_RECOV_N")
		)
		(pad "2" smd circle
			(at 0.40005 0)
			(size 0 0)
			(layers "F.Cu" "F.Mask" "F.Paste")
			(net "GPU_FPGA_EROT_RECOV_R_N")
		)
	)
)
